# BASEBOARD_FAB2 (Tioga Pass) — schematic netlist excerpt (pin names and nets, part order shuffled) for the footprints in the layout excerpt that follows; sources: Cadence DE-HDL packaged netlist, KiCad conversion of Wiwynn_Tioga_Pass_MB.brd

C7E2  CAP_A  0.1UF 16V 10% X7R  pkg 0402V  page 99 : A = PVPP_DEF ; B = GND
C3M36  CAP  0.22UF 16V 10% X7R  pkg 0402  page 105 : A = P3E_CPU0_PE1_PCH_R_RXP<9> ; B = P3E_CPU0_PE1_PCH_RXP<9>

(kicad_pcb
	(version 20260206)
	(generator "pcbnew")
	(generator_version "10.0")
	(general
		(thickness 1.6)
		(legacy_teardrops no)
	)
	(paper "A4")
	(title_block
		(title "Wiwynn_Tioga_Pass_MB.brd")
		(comment 1 "Tioga Pass / footprints 3089-3090 of 4770")
	)
	(layers
		(0 "F.Cu" signal "TOP")
		(4 "In1.Cu" signal "L2GND")
		(6 "In2.Cu" signal "L3")
		(8 "In3.Cu" signal "L4GND")
		(10 "In4.Cu" signal "L5")
		(12 "In5.Cu" signal "L6GND")
		(14 "In6.Cu" signal "L7VCC")
		(16 "In7.Cu" signal "L8VCC")
		(18 "In8.Cu" signal "L9GND")
		(20 "In9.Cu" signal "L10")
		(22 "In10.Cu" signal "L11GND")
		(24 "In11.Cu" signal "L12")
		(26 "In12.Cu" signal "L13GND")
		(2 "B.Cu" signal "BOTTOM")
		(9 "F.Adhes" user "F.Adhesive")
		(11 "B.Adhes" user "B.Adhesive")
		(13 "F.Paste" user "Package Geometry/Pastemask Top")
		(15 "B.Paste" user "Package Geometry/Pastemask Bottom")
		(5 "F.SilkS" user "Ref Des/Silkscreen Top")
		(7 "B.SilkS" user "Ref Des/Silkscreen Bottom")
		(1 "F.Mask" user "Board Geometry/Soldermask Top")
		(3 "B.Mask" user "Board Geometry/Soldermask Bottom")
		(17 "Dwgs.User" user "User.Drawings")
		(19 "Cmts.User" user "User.Comments")
		(21 "Eco1.User" user "User.Eco1")
		(23 "Eco2.User" user "User.Eco2")
		(25 "Edge.Cuts" user "Board Geometry/Outline")
		(27 "Margin" user)
		(31 "F.CrtYd" user "Package Geometry/Place Bound Top")
		(29 "B.CrtYd" user "Package Geometry/Place Bound Bottom")
		(35 "F.Fab" user "Ref Des/Assembly Top")
		(33 "B.Fab" user "Ref Des/Assembly Bottom")
	)
	(footprint ""
		(layer "B.Cu")
		(at 368.716814 -124.389642 -90)
		(property "Reference" "C3M36"
			(at 0 0 90)
			(layer "B.SilkS")
			(hide yes)
			(effects
				(font
					(size 1.27 1.27)
				)
				(justify mirror)
			)
		)
		(property "Value" ""
			(at 0 0 90)
			(layer "B.Fab")
			(effects
				(font
					(size 1.27 1.27)
				)
				(justify mirror)
			)
		)
		(duplicate_pad_numbers_are_jumpers no)
		(fp_poly
			(pts
				(xy -0.3048 -0.1016) (xy -0.3048 0.9906) (xy 0.3048 0.9906) (xy 0.3048 -0.1016)
			)
			(stroke
				(width 0)
				(type default)
			)
			(fill no)
			(layer "B.CrtYd")
		)
		(fp_line
			(start -0.3048 0.9906)
			(end -0.3048 -0.1016)
			(stroke
				(width 0.1)
				(type default)
			)
			(layer "B.Fab")
		)
		(fp_line
			(start 0.3048 0.9906)
			(end -0.3048 0.9906)
			(stroke
				(width 0.1)
				(type default)
			)
			(layer "B.Fab")
		)
		(fp_line
			(start -0.3048 -0.1016)
			(end 0.3048 -0.1016)
			(stroke
				(width 0.1)
				(type default)
			)
			(layer "B.Fab")
		)
		(fp_line
			(start 0.3048 -0.1016)
			(end 0.3048 0.9906)
			(stroke
				(width 0.1)
				(type default)
			)
			(layer "B.Fab")
		)
		(pad "1" smd rect
			(at 0 0 90)
			(size 0.508 0.508)
			(layers "B.Cu" "B.Mask" "B.Paste")
			(net "P3E_CPU0_PE1_PCH_R_RXP<9>")
		)
		(pad "2" smd rect
			(at 0 0.889 90)
			(size 0.508 0.508)
			(layers "B.Cu" "B.Mask" "B.Paste")
			(net "P3E_CPU0_PE1_PCH_RXP<9>")
		)
		(zone
			(layer "B.Cu")
			(hatch none 0.5)
			(connect_pads
				(clearance 0)
			)
			(min_thickness 0.25)
			(keepout
				(tracks not_allowed)
				(vias allowed)
				(pads allowed)
				(copperpour not_allowed)
				(footprints allowed)
			)
			(placement
				(enabled no)
				(sheetname "")
			)
			(fill
				(thermal_gap 0.5)
				(thermal_bridge_width 0.5)
				(island_removal_mode 0)
			)
			(polygon
				(pts
					(xy 368.081814 -124.135642) (xy 368.081814 -124.643642) (xy 368.462814 -124.643642) (xy 368.462814 -124.135642)
				)
			)
		)
		(zone
			(layer "B.Cu")
			(hatch none 0.5)
			(connect_pads
				(clearance 0)
			)
			(min_thickness 0.25)
			(keepout
				(tracks allowed)
				(vias not_allowed)
				(pads allowed)
				(copperpour not_allowed)
				(footprints allowed)
			)
			(placement
				(enabled no)
				(sheetname "")
			)
			(fill
				(thermal_gap 0.5)
				(thermal_bridge_width 0.5)
				(island_removal_mode 0)
			)
			(polygon
				(pts
					(xy 368.462814 -124.135642) (xy 368.462814 -124.643642) (xy 368.081814 -124.643642) (xy 368.081814 -124.135642)
				)
			)
		)
	)
	(footprint ""
		(layer "B.Cu")
		(at 321.2338 -124.115322 180)
		(property "Reference" "C7E2"
			(at 0 0 0)
			(layer "B.SilkS")
			(hide yes)
			(effects
				(font
					(size 1.27 1.27)
				)
				(justify mirror)
			)
		)
		(property "Value" ""
			(at 0 0 0)
			(layer "B.Fab")
			(effects
				(font
					(size 1.27 1.27)
				)
				(justify mirror)
			)
		)
		(duplicate_pad_numbers_are_jumpers no)
		(fp_poly
			(pts
				(xy -0.3048 -0.1016) (xy -0.3048 0.9906) (xy 0.3048 0.9906) (xy 0.3048 -0.1016)
			)
			(stroke
				(width 0)
				(type default)
			)
			(fill no)
			(layer "B.CrtYd")
		)
		(fp_line
			(start 0.3048 0.9906)
			(end -0.3048 0.9906)
			(stroke
				(width 0.1)
				(type default)
			)
			(layer "B.Fab")
		)
		(fp_line
			(start 0.3048 -0.1016)
			(end 0.3048 0.9906)
			(stroke
				(width 0.1)
				(type default)
			)
			(layer "B.Fab")
		)
		(fp_line
			(start -0.3048 0.9906)
			(end -0.3048 -0.1016)
			(stroke
				(width 0.1)
				(type default)
			)
			(layer "B.Fab")
		)
		(fp_line
			(start -0.3048 -0.1016)
			(end 0.3048 -0.1016)
			(stroke
				(width 0.1)
				(type default)
			)
			(layer "B.Fab")
		)
		(pad "1" smd rect
			(at 0 0)
			(size 0.508 0.508)
			(layers "B.Cu" "B.Mask" "B.Paste")
			(net "PVPP_DEF")
		)
		(pad "2" smd rect
			(at 0 0.889)
			(size 0.508 0.508)
			(layers "B.Cu" "B.Mask" "B.Paste")
			(net "GND")
		)
		(zone
			(layer "B.Cu")
			(hatch none 0.5)
			(connect_pads
				(clearance 0)
			)
			(min_thickness 0.25)
			(keepout
				(tracks not_allowed)
				(vias allowed)
				(pads allowed)
				(copperpour not_allowed)
				(footprints allowed)
			)
			(placement
				(enabled no)
				(sheetname "")
			)
			(fill
				(thermal_gap 0.5)
				(thermal_bridge_width 0.5)
				(island_removal_mode 0)
			)
			(polygon
				(pts
					(xy 320.9798 -124.750322) (xy 321.4878 -124.750322) (xy 321.4878 -124.369322) (xy 320.9798 -124.369322)
				)
			)
		)
		(zone
			(layer "B.Cu")
			(hatch none 0.5)
			(connect_pads
				(clearance 0)
			)
			(min_thickness 0.25)
			(keepout
				(tracks allowed)
				(vias not_allowed)
				(pads allowed)
				(copperpour not_allowed)
				(footprints allowed)
			)
			(placement
				(enabled no)
				(sheetname "")
			)
			(fill
				(thermal_gap 0.5)
				(thermal_bridge_width 0.5)
				(island_removal_mode 0)
			)
			(polygon
				(pts
					(xy 320.9798 -124.369322) (xy 321.4878 -124.369322) (xy 321.4878 -124.750322) (xy 320.9798 -124.750322)
				)
			)
		)
	)
)
